(kicad_pcb
	(version 20260206)
	(generator "pcbnew")
	(generator_version "10.0")
	(general
		(thickness 1.6)
		(legacy_teardrops no)
	)
	(paper "A4")
	(title_block
		(title "01162023_DA0F0TEBIF0_F0T_Expander_BD_F_brd_V02_OCP.brd")
		(comment 1 "Grand Teton / footprints 1290-1294 of 9728")
	)
	(layers
		(0 "F.Cu" signal "TOP")
		(4 "In1.Cu" signal "GND")
		(6 "In2.Cu" signal "VCC")
		(8 "In3.Cu" signal "VCC1")
		(10 "In4.Cu" signal "GND1")
		(12 "In5.Cu" signal "IN1")
		(14 "In6.Cu" signal "GND2")
		(16 "In7.Cu" signal "IN2")
		(18 "In8.Cu" signal "GND3")
		(20 "In9.Cu" signal "IN3")
		(22 "In10.Cu" signal "GND4")
		(24 "In11.Cu" signal "IN4")
		(26 "In12.Cu" signal "GND5")
		(28 "In13.Cu" signal "IN5")
		(30 "In14.Cu" signal "GND6")
		(32 "In15.Cu" signal "IN6")
		(34 "In16.Cu" signal "GND7")
		(2 "B.Cu" signal "BOTTOM")
		(9 "F.Adhes" user "F.Adhesive")
		(11 "B.Adhes" user "B.Adhesive")
		(13 "F.Paste" user "Package Geometry/Pastemask Top")
		(15 "B.Paste" user "Package Geometry/Pastemask Bottom")
		(5 "F.SilkS" user "Ref Des/Silkscreen Top")
		(7 "B.SilkS" user "Ref Des/Silkscreen Bottom")
		(1 "F.Mask" user "Board Geometry/Soldermask Top")
		(3 "B.Mask" user "Board Geometry/Soldermask Bottom")
		(17 "Dwgs.User" user "User.Drawings")
		(19 "Cmts.User" user "User.Comments")
		(21 "Eco1.User" user "User.Eco1")
		(23 "Eco2.User" user "User.Eco2")
		(25 "Edge.Cuts" user "Board Geometry/Outline")
		(27 "Margin" user)
		(31 "F.CrtYd" user "Package Geometry/Place Bound Top")
		(29 "B.CrtYd" user "Package Geometry/Place Bound Bottom")
		(35 "F.Fab" user "Ref Des/Assembly Top")
		(33 "B.Fab" user "Ref Des/Assembly Bottom")
	)
	(footprint ""
		(layer "F.Cu")
		(at 87.006684 -294.77335 90)
		(property "Reference" "U425"
			(at -1.0922 -2.174748 90)
			(unlocked yes)
			(layer "F.SilkS")
			(effects
				(font
					(size 0.7874 0.5842)
					(thickness 0.1524)
				)
				(justify left)
			)
		)
		(property "Value" ""
			(at 0 0 90)
			(layer "F.Fab")
			(effects
				(font
					(size 1.27 1.27)
				)
			)
		)
		(duplicate_pad_numbers_are_jumpers no)
		(fp_line
			(start 1.0414 -1.575054)
			(end 1.0414 1.575054)
			(stroke
				(width 0.1524)
				(type default)
			)
			(layer "F.SilkS")
		)
		(fp_line
			(start 0.254 -1.575054)
			(end 1.0414 -1.575054)
			(stroke
				(width 0.1524)
				(type default)
			)
			(layer "F.SilkS")
		)
		(fp_line
			(start 0.2286 -1.575054)
			(end 0 -1.272032)
			(stroke
				(width 0.1524)
				(type default)
			)
			(layer "F.SilkS")
		)
		(fp_line
			(start -1.0414 -1.575054)
			(end -0.254 -1.575054)
			(stroke
				(width 0.1524)
				(type default)
			)
			(layer "F.SilkS")
		)
		(fp_line
			(start 0 -1.272032)
			(end -0.254 -1.575054)
			(stroke
				(width 0.1524)
				(type default)
			)
			(layer "F.SilkS")
		)
		(fp_line
			(start 1.0414 1.575054)
			(end -1.0414 1.575054)
			(stroke
				(width 0.1524)
				(type default)
			)
			(layer "F.SilkS")
		)
		(fp_line
			(start -1.0414 1.575054)
			(end -1.0414 -1.575054)
			(stroke
				(width 0.1524)
				(type default)
			)
			(layer "F.SilkS")
		)
		(fp_poly
			(pts
				(xy -2.710688 -0.975106) (xy -3.726688 -1.483106) (xy -3.726688 -0.467106)
			)
			(stroke
				(width 0)
				(type default)
			)
			(fill yes)
			(layer "F.SilkS")
		)
		(fp_line
			(start 1.4478 -1.5748)
			(end 1.4478 -1.2192)
			(stroke
				(width 0.1)
				(type default)
			)
			(layer "F.Fab")
		)
		(fp_line
			(start -1.4478 -1.5748)
			(end 1.4478 -1.5748)
			(stroke
				(width 0.1)
				(type default)
			)
			(layer "F.Fab")
		)
		(fp_line
			(start 2.5654 -1.2192)
			(end 2.5654 1.2192)
			(stroke
				(width 0.1)
				(type default)
			)
			(layer "F.Fab")
		)
		(fp_line
			(start 1.4478 -1.2192)
			(end 2.5654 -1.2192)
			(stroke
				(width 0.1)
				(type default)
			)
			(layer "F.Fab")
		)
		(fp_line
			(start -1.4478 -1.2192)
			(end -1.4478 -1.5748)
			(stroke
				(width 0.1)
				(type default)
			)
			(layer "F.Fab")
		)
		(fp_line
			(start -2.5654 -1.2192)
			(end -1.4478 -1.2192)
			(stroke
				(width 0.1)
				(type default)
			)
			(layer "F.Fab")
		)
		(fp_line
			(start 2.5654 1.2192)
			(end 1.4478 1.2192)
			(stroke
				(width 0.1)
				(type default)
			)
			(layer "F.Fab")
		)
		(fp_line
			(start 1.4478 1.2192)
			(end 1.4478 1.5748)
			(stroke
				(width 0.1)
				(type default)
			)
			(layer "F.Fab")
		)
		(fp_line
			(start -1.4478 1.2192)
			(end -2.5654 1.2192)
			(stroke
				(width 0.1)
				(type default)
			)
			(layer "F.Fab")
		)
		(fp_line
			(start -2.5654 1.2192)
			(end -2.5654 -1.2192)
			(stroke
				(width 0.1)
				(type default)
			)
			(layer "F.Fab")
		)
		(fp_line
			(start 1.4478 1.5748)
			(end -1.4478 1.5748)
			(stroke
				(width 0.1)
				(type default)
			)
			(layer "F.Fab")
		)
		(fp_line
			(start -1.4478 1.5748)
			(end -1.4478 1.2192)
			(stroke
				(width 0.1)
				(type default)
			)
			(layer "F.Fab")
		)
		(fp_poly
			(pts
				(xy -2.710688 -0.975106) (xy -3.726688 -1.483106) (xy -3.726688 -0.467106)
			)
			(stroke
				(width 0)
				(type default)
			)
			(fill yes)
			(layer "F.Fab")
		)
		(pad "1" smd rect
			(at -1.849882 -0.975106)
			(size 0.3556 1.3208)
			(layers "F.Cu" "F.Mask" "F.Paste")
			(net "RST_PEX0_PERST_R_N")
		)
		(pad "2" smd rect
			(at -1.849882 -0.32512)
			(size 0.3556 1.3208)
			(layers "F.Cu" "F.Mask" "F.Paste")
			(net "RST_PEX0_S0_PERST_N")
		)
		(pad "3" smd rect
			(at -1.849882 0.32512)
			(size 0.3556 1.3208)
			(layers "F.Cu" "F.Mask" "F.Paste")
			(net "RST_PEX0_PERST_R_N")
		)
		(pad "4" smd rect
			(at -1.849882 0.975106)
			(size 0.3556 1.3208)
			(layers "F.Cu" "F.Mask" "F.Paste")
			(net "GND")
		)
		(pad "5" smd rect
			(at 1.849882 0.975106)
			(size 0.3556 1.3208)
			(layers "F.Cu" "F.Mask" "F.Paste")
			(net "RST_PEX0_S1_PERST_N")
		)
		(pad "6" smd rect
			(at 1.849882 0.32512)
			(size 0.3556 1.3208)
			(layers "F.Cu" "F.Mask" "F.Paste")
			(net "RST_PEX0_PERST_R_N")
		)
		(pad "7" smd rect
			(at 1.849882 -0.32512)
			(size 0.3556 1.3208)
			(layers "F.Cu" "F.Mask" "F.Paste")
			(net "RST_PEX0_S3_PERST_N")
		)
		(pad "8" smd rect
			(at 1.849882 -0.975106)
			(size 0.3556 1.3208)
			(layers "F.Cu" "F.Mask" "F.Paste")
			(net "P1V8_PEX")
		)
	)
	(footprint ""
		(layer "F.Cu")
		(at 199.955658 -237.187232)
		(property "Reference" "J60"
			(at -1.4224 -4.562348 0)
			(unlocked yes)
			(layer "F.SilkS")
			(effects
				(font
					(size 0.7874 0.5842)
					(thickness 0.1524)
				)
				(justify left)
			)
		)
		(property "Value" ""
			(at 0 0 0)
			(layer "F.Fab")
			(effects
				(font
					(size 1.27 1.27)
				)
			)
		)
		(duplicate_pad_numbers_are_jumpers no)
		(fp_line
			(start -1.27 -3.81)
			(end 1.27 -3.81)
			(stroke
				(width 0.1524)
				(type default)
			)
			(layer "F.SilkS")
		)
		(fp_line
			(start -1.27 -0.7747)
			(end -1.27 -3.81)
			(stroke
				(width 0.1524)
				(type default)
			)
			(layer "F.SilkS")
		)
		(fp_line
			(start -1.27 3.81)
			(end -1.27 0.7747)
			(stroke
				(width 0.1524)
				(type default)
			)
			(layer "F.SilkS")
		)
		(fp_line
			(start 1.27 -3.81)
			(end 1.27 -3.3147)
			(stroke
				(width 0.1524)
				(type default)
			)
			(layer "F.SilkS")
		)
		(fp_line
			(start 1.27 -1.7653)
			(end 1.27 1.7653)
			(stroke
				(width 0.1524)
				(type default)
			)
			(layer "F.SilkS")
		)
		(fp_line
			(start 1.27 3.3147)
			(end 1.27 3.81)
			(stroke
				(width 0.1524)
				(type default)
			)
			(layer "F.SilkS")
		)
		(fp_line
			(start 1.27 3.81)
			(end -1.27 3.81)
			(stroke
				(width 0.1524)
				(type default)
			)
			(layer "F.SilkS")
		)
		(fp_poly
			(pts
				(xy 4.3942 -3.048) (xy 4.3942 -2.032) (xy 3.3782 -2.54)
			)
			(stroke
				(width 0)
				(type default)
			)
			(fill yes)
			(layer "F.SilkS")
		)
		(fp_line
			(start -1.27 -3.81)
			(end -1.27 3.81)
			(stroke
				(width 0.1)
				(type default)
			)
			(layer "F.Fab")
		)
		(fp_line
			(start -1.27 3.81)
			(end 1.27 3.81)
			(stroke
				(width 0.1)
				(type default)
			)
			(layer "F.Fab")
		)
		(fp_line
			(start 1.27 -3.81)
			(end -1.27 -3.81)
			(stroke
				(width 0.1)
				(type default)
			)
			(layer "F.Fab")
		)
		(fp_line
			(start 1.27 3.81)
			(end 1.27 -3.81)
			(stroke
				(width 0.1)
				(type default)
			)
			(layer "F.Fab")
		)
		(fp_poly
			(pts
				(xy 4.3942 -3.048) (xy 4.3942 -2.032) (xy 3.3782 -2.54)
			)
			(stroke
				(width 0)
				(type default)
			)
			(fill yes)
			(layer "F.Fab")
		)
		(fp_text user "3"
			(at 3.921252 2.54 90)
			(unlocked yes)
			(layer "F.SilkS")
			(effects
				(font
					(size 0.7874 0.5842)
					(thickness 0.1524)
				)
			)
		)
		(fp_text user "3"
			(at 3.921252 2.54 90)
			(unlocked yes)
			(layer "F.Fab")
			(effects
				(font
					(size 0.7874 0.5842)
					(thickness 0.1524)
				)
			)
		)
		(pad "1" smd rect
			(at 1.459992 -2.54 90)
			(size 1.27 3.429)
			(layers "F.Cu" "F.Mask" "F.Paste")
			(net "BIC_UART_SW_SEL1_R")
		)
		(pad "2" smd rect
			(at -1.459992 0 90)
			(size 1.27 3.429)
			(layers "F.Cu" "F.Mask" "F.Paste")
			(net "BIC_UART_SEL1")
		)
		(pad "3" smd rect
			(at 1.459992 2.54 90)
			(size 1.27 3.429)
			(layers "F.Cu" "F.Mask" "F.Paste")
			(net "BIC_UART_HW_SEL1")
		)
	)
	(footprint ""
		(layer "F.Cu")
		(at 214.675466 -69.47916 180)
		(property "Reference" "PU110"
			(at -1.937004 4.18084 90)
			(unlocked yes)
			(layer "F.SilkS")
			(effects
				(font
					(size 0.7874 0.5842)
					(thickness 0.1524)
				)
			)
		)
		(property "Value" ""
			(at 0 0 180)
			(layer "F.Fab")
			(effects
				(font
					(size 1.27 1.27)
				)
			)
		)
		(duplicate_pad_numbers_are_jumpers no)
		(fp_line
			(start 1.239774 1.495298)
			(end -1.239774 1.495298)
			(stroke
				(width 0.1524)
				(type default)
			)
			(layer "F.SilkS")
		)
		(fp_line
			(start 1.239774 -1.495298)
			(end 1.239774 1.495298)
			(stroke
				(width 0.1524)
				(type default)
			)
			(layer "F.SilkS")
		)
		(fp_line
			(start -1.239774 1.495298)
			(end -1.239774 -1.495298)
			(stroke
				(width 0.1524)
				(type default)
			)
			(layer "F.SilkS")
		)
		(fp_line
			(start -1.239774 -1.495298)
			(end 1.239774 -1.495298)
			(stroke
				(width 0.1524)
				(type default)
			)
			(layer "F.SilkS")
		)
		(fp_poly
			(pts
				(xy -1.801622 -1.255268) (xy -2.520188 -0.536956) (xy -1.442466 -0.1778)
			)
			(stroke
				(width 0)
				(type default)
			)
			(fill yes)
			(layer "F.SilkS")
		)
		(fp_line
			(start 0.8001 1.050036)
			(end -0.8001 1.050036)
			(stroke
				(width 0.1)
				(type default)
			)
			(layer "F.Fab")
		)
		(fp_line
			(start 0.8001 -1.050036)
			(end 0.8001 1.050036)
			(stroke
				(width 0.1)
				(type default)
			)
			(layer "F.Fab")
		)
		(fp_line
			(start -0.8001 1.050036)
			(end -0.8001 -1.050036)
			(stroke
				(width 0.1)
				(type default)
			)
			(layer "F.Fab")
		)
		(fp_line
			(start -0.8001 -1.050036)
			(end 0.8001 -1.050036)
			(stroke
				(width 0.1)
				(type default)
			)
			(layer "F.Fab")
		)
		(fp_poly
			(pts
				(xy -2.458974 -0.508) (xy -2.458974 0.508) (xy -1.442974 0)
			)
			(stroke
				(width 0)
				(type default)
			)
			(fill yes)
			(layer "F.Fab")
		)
		(pad "1_2" smd circle
			(at -0.374904 0 270)
			(size 0 0)
			(layers "F.Cu" "F.Mask" "F.Paste")
			(net "P12V_AUX")
		)
		(pad "3" smd rect
			(at -0.499872 0.999998 180)
			(size 0.254 0.7112)
			(layers "F.Cu" "F.Mask" "F.Paste")
			(net "GND")
		)
		(pad "4" smd rect
			(at 0 0.999998 180)
			(size 0.254 0.7112)
			(layers "F.Cu" "F.Mask" "F.Paste")
			(net "P12V_SSD7_CO_ILIMIT")
		)
		(pad "5" smd rect
			(at 0.499872 0.999998 180)
			(size 0.254 0.7112)
			(layers "F.Cu" "F.Mask" "F.Paste")
			(net "P12V_SSD7_CO_MODE")
		)
		(pad "6_7" smd circle
			(at 0.374904 0 90)
			(size 0 0)
			(layers "F.Cu" "F.Mask" "F.Paste")
			(net "P12V_SSD7_R")
		)
		(pad "8" smd rect
			(at 0.499872 -0.999998 180)
			(size 0.254 0.7112)
			(layers "F.Cu" "F.Mask" "F.Paste")
			(net "P12V_SSD7_CO_GATE")
		)
		(pad "9" smd rect
			(at 0 -0.999998 180)
			(size 0.254 0.7112)
			(layers "F.Cu" "F.Mask" "F.Paste")
			(net "P12V_SSD7_CO_EN")
		)
		(pad "10" smd rect
			(at -0.499872 -0.999998 180)
			(size 0.254 0.7112)
			(layers "F.Cu" "F.Mask" "F.Paste")
			(net "P12V_SSD7_CO_DV_DT")
		)
	)
	(footprint ""
		(layer "F.Cu")
		(at 357.988108 -208.233518 180)
		(property "Reference" "R6423"
			(at 0 0 180)
			(layer "F.SilkS")
			(hide yes)
			(effects
				(font
					(size 1.27 1.27)
				)
			)
		)
		(property "Value" ""
			(at 0 0 180)
			(layer "F.Fab")
			(effects
				(font
					(size 1.27 1.27)
				)
			)
		)
		(duplicate_pad_numbers_are_jumpers no)
		(fp_line
			(start 0.7874 0.4064)
			(end -0.7874 0.4064)
			(stroke
				(width 0.1524)
				(type default)
			)
			(layer "F.SilkS")
		)
		(fp_line
			(start 0.7874 -0.4064)
			(end 0.7874 0.4064)
			(stroke
				(width 0.1524)
				(type default)
			)
			(layer "F.SilkS")
		)
		(fp_line
			(start -0.7874 0.4064)
			(end -0.7874 -0.4064)
			(stroke
				(width 0.1524)
				(type default)
			)
			(layer "F.SilkS")
		)
		(fp_line
			(start -0.7874 -0.4064)
			(end 0.7874 -0.4064)
			(stroke
				(width 0.1524)
				(type default)
			)
			(layer "F.SilkS")
		)
		(fp_line
			(start 0.67945 0.3048)
			(end 0.120396 0.3048)
			(stroke
				(width 0.1)
				(type default)
			)
			(layer "F.Fab")
		)
		(fp_line
			(start 0.67945 -0.3048)
			(end 0.67945 0.3048)
			(stroke
				(width 0.1)
				(type default)
			)
			(layer "F.Fab")
		)
		(fp_line
			(start 0.12065 -0.2794)
			(end 0.12065 -0.3048)
			(stroke
				(width 0.1)
				(type default)
			)
			(layer "F.Fab")
		)
		(fp_line
			(start 0.12065 -0.3048)
			(end 0.67945 -0.3048)
			(stroke
				(width 0.1)
				(type default)
			)
			(layer "F.Fab")
		)
		(fp_line
			(start 0.120396 0.3048)
			(end 0.120396 0.2794)
			(stroke
				(width 0.1)
				(type default)
			)
			(layer "F.Fab")
		)
		(fp_line
			(start 0.120396 0.2794)
			(end -0.12065 0.2794)
			(stroke
				(width 0.1)
				(type default)
			)
			(layer "F.Fab")
		)
		(fp_line
			(start -0.12065 0.3048)
			(end -0.67945 0.3048)
			(stroke
				(width 0.1)
				(type default)
			)
			(layer "F.Fab")
		)
		(fp_line
			(start -0.12065 0.2794)
			(end -0.12065 0.3048)
			(stroke
				(width 0.1)
				(type default)
			)
			(layer "F.Fab")
		)
		(fp_line
			(start -0.12065 -0.2794)
			(end 0.12065 -0.2794)
			(stroke
				(width 0.1)
				(type default)
			)
			(layer "F.Fab")
		)
		(fp_line
			(start -0.12065 -0.305054)
			(end -0.12065 -0.2794)
			(stroke
				(width 0.1)
				(type default)
			)
			(layer "F.Fab")
		)
		(fp_line
			(start -0.67945 0.3048)
			(end -0.67945 -0.305054)
			(stroke
				(width 0.1)
				(type default)
			)
			(layer "F.Fab")
		)
		(fp_line
			(start -0.67945 -0.305054)
			(end -0.12065 -0.305054)
			(stroke
				(width 0.1)
				(type default)
			)
			(layer "F.Fab")
		)
		(pad "1" smd circle
			(at -0.40005 0 180)
			(size 0 0)
			(layers "F.Cu" "F.Mask" "F.Paste")
			(net "FPGA_PEX3_MODE_SEL1_R")
		)
		(pad "2" smd circle
			(at 0.40005 0 180)
			(size 0 0)
			(layers "F.Cu" "F.Mask" "F.Paste")
			(net "FPGA_PEX3_MODE_SEL1")
		)
	)
	(footprint ""
		(layer "F.Cu")
		(at 239.345724 -181.87035 90)
		(property "Reference" "U358"
			(at 1.97485 0.736346 90)
			(unlocked yes)
			(layer "F.SilkS")
			(effects
				(font
					(size 0.7874 0.5842)
					(thickness 0.1524)
				)
				(justify left)
			)
		)
		(property "Value" ""
			(at 0 0 90)
			(layer "F.Fab")
			(effects
				(font
					(size 1.27 1.27)
				)
			)
		)
		(duplicate_pad_numbers_are_jumpers no)
		(fp_line
			(start 0.700024 -1.519936)
			(end 0.700024 -1.3716)
			(stroke
				(width 0.1524)
				(type default)
			)
			(layer "F.SilkS")
		)
		(fp_line
			(start -0.700024 -1.519936)
			(end 0.700024 -1.519936)
			(stroke
				(width 0.1524)
				(type default)
			)
			(layer "F.SilkS")
		)
		(fp_line
			(start -0.700024 -1.3716)
			(end -0.700024 -1.519936)
			(stroke
				(width 0.1524)
				(type default)
			)
			(layer "F.SilkS")
		)
		(fp_line
			(start 0.700024 -0.5334)
			(end 0.700024 0.5334)
			(stroke
				(width 0.1524)
				(type default)
			)
			(layer "F.SilkS")
		)
		(fp_line
			(start -0.700024 0.5334)
			(end -0.700024 -0.127)
			(stroke
				(width 0.1524)
				(type default)
			)
			(layer "F.SilkS")
		)
		(fp_line
			(start 0.700024 1.3716)
			(end 0.700024 1.519936)
			(stroke
				(width 0.1524)
				(type default)
			)
			(layer "F.SilkS")
		)
		(fp_line
			(start 0.700024 1.519936)
			(end -0.700024 1.519936)
			(stroke
				(width 0.1524)
				(type default)
			)
			(layer "F.SilkS")
		)
		(fp_line
			(start -0.700024 1.519936)
			(end -0.700024 1.3716)
			(stroke
				(width 0.1524)
				(type default)
			)
			(layer "F.SilkS")
		)
		(fp_poly
			(pts
				(xy -2.926842 -0.517398) (xy -2.926842 -1.142238) (xy -2.373122 -0.81407)
			)
			(stroke
				(width 0)
				(type default)
			)
			(fill yes)
			(layer "F.SilkS")
		)
		(fp_line
			(start 0.700024 -1.519936)
			(end 0.700024 1.519936)
			(stroke
				(width 0.1)
				(type default)
			)
			(layer "F.Fab")
		)
		(fp_line
			(start -0.700024 -1.519936)
			(end 0.700024 -1.519936)
			(stroke
				(width 0.1)
				(type default)
			)
			(layer "F.Fab")
		)
		(fp_line
			(start 0.700024 1.519936)
			(end -0.700024 1.519936)
			(stroke
				(width 0.1)
				(type default)
			)
			(layer "F.Fab")
		)
		(fp_line
			(start -0.700024 1.519936)
			(end -0.700024 -1.519936)
			(stroke
				(width 0.1)
				(type default)
			)
			(layer "F.Fab")
		)
		(fp_poly
			(pts
				(xy -2.45872 -0.465328) (xy -2.45872 -1.090168) (xy -1.905 -0.762)
			)
			(stroke
				(width 0)
				(type default)
			)
			(fill yes)
			(layer "F.Fab")
		)
		(pad "1" smd rect
			(at -0.985012 -0.759968)
			(size 0.9652 1.4224)
			(layers "F.Cu" "F.Mask" "F.Paste")
			(net "GND")
		)
		(pad "2" smd rect
			(at -0.985012 0.96012)
			(size 0.5588 1.4224)
			(layers "F.Cu" "F.Mask" "F.Paste")
			(net "BIC_RST_RSMRST_N")
		)
		(pad "3" smd rect
			(at 0.985012 0.96012)
			(size 0.5588 1.4224)
			(layers "F.Cu" "F.Mask" "F.Paste")
			(net "Net_8960")
		)
		(pad "4" smd rect
			(at 0.985012 -0.96012)
			(size 0.5588 1.4224)
			(layers "F.Cu" "F.Mask" "F.Paste")
			(net "P3V3_AUX")
		)
	)
)
